(kicad_pcb
	(version 20260206)
	(generator "pcbnew")
	(generator_version "10.0")
	(general
		(thickness 1.6)
		(legacy_teardrops no)
	)
	(paper "A4")
	(title_block
		(title "03242023_DA0F0TMBIJ0_F0T_Motherboard_J_brd_V01_OCP.brd")
		(comment 1 "Grand Teton / footprint 3039 of 6105 (U2), pads 1382-1492 of 4677")
	)
	(layers
		(0 "F.Cu" signal "TOP")
		(4 "In1.Cu" signal "GND")
		(6 "In2.Cu" signal "IN1")
		(8 "In3.Cu" signal "GND1")
		(10 "In4.Cu" signal "IN2")
		(12 "In5.Cu" signal "GND2")
		(14 "In6.Cu" signal "IN3")
		(16 "In7.Cu" signal "GND3")
		(18 "In8.Cu" signal "VCC")
		(20 "In9.Cu" signal "VCC1")
		(22 "In10.Cu" signal "GND4")
		(24 "In11.Cu" signal "IN4")
		(26 "In12.Cu" signal "GND5")
		(28 "In13.Cu" signal "IN5")
		(30 "In14.Cu" signal "GND6")
		(32 "In15.Cu" signal "IN6")
		(34 "In16.Cu" signal "GND7")
		(2 "B.Cu" signal "BOTTOM")
		(9 "F.Adhes" user "F.Adhesive")
		(11 "B.Adhes" user "B.Adhesive")
		(13 "F.Paste" user "Package Geometry/Pastemask Top")
		(15 "B.Paste" user "Package Geometry/Pastemask Bottom")
		(5 "F.SilkS" user "Ref Des/Silkscreen Top")
		(7 "B.SilkS" user "Ref Des/Silkscreen Bottom")
		(1 "F.Mask" user "Board Geometry/Soldermask Top")
		(3 "B.Mask" user "Board Geometry/Soldermask Bottom")
		(17 "Dwgs.User" user "User.Drawings")
		(19 "Cmts.User" user "User.Comments")
		(21 "Eco1.User" user "User.Eco1")
		(23 "Eco2.User" user "User.Eco2")
		(25 "Edge.Cuts" user "Board Geometry/Outline")
		(27 "Margin" user)
		(31 "F.CrtYd" user "Package Geometry/Place Bound Top")
		(29 "B.CrtYd" user "Package Geometry/Place Bound Bottom")
		(35 "F.Fab" user "Ref Des/Assembly Top")
		(33 "B.Fab" user "Ref Des/Assembly Bottom")
	)
	(footprint ""
		(layer "F.Cu")
		(at 359.870248 -251.76988 90)
		(property "Reference" "U2"
			(at -74.416158 -44.488608 0)
			(unlocked yes)
			(layer "F.SilkS")
			(effects
				(font
					(size 1.6002 1.1938)
					(thickness 0.1524)
				)
				(justify left)
			)
		)
		(property "Value" ""
			(at 0 0 90)
			(layer "F.Fab")
			(effects
				(font
					(size 1.27 1.27)
				)
			)
		)
		(duplicate_pad_numbers_are_jumpers no)
		(pad "BR25" smd circle
			(at -17.89176 -1.699514 270)
			(size 0.4318 0.4318)
			(layers "F.Cu" "F.Mask" "F.Paste")
			(net "JTAG_DBP_CPU0_QS_GTL_R_TMS")
		)
		(pad "BR27" smd circle
			(at -16.263874 -1.699514 270)
			(size 0.4318 0.4318)
			(layers "F.Cu" "F.Mask" "F.Paste")
			(net "GND")
		)
		(pad "BR29" smd circle
			(at -14.635988 -1.699514 270)
			(size 0.4318 0.4318)
			(layers "F.Cu" "F.Mask" "F.Paste")
			(net "GND")
		)
		(pad "BR31" smd circle
			(at -13.008356 -1.699514 270)
			(size 0.4318 0.4318)
			(layers "F.Cu" "F.Mask" "F.Paste")
			(net "GND")
		)
		(pad "BR33" smd circle
			(at -11.380724 -1.699514 270)
			(size 0.4318 0.4318)
			(layers "F.Cu" "F.Mask" "F.Paste")
			(net "GND")
		)
		(pad "BR35" smd circle
			(at -9.752838 -1.699514 270)
			(size 0.4318 0.4318)
			(layers "F.Cu" "F.Mask" "F.Paste")
			(net "GND")
		)
		(pad "BR37" smd circle
			(at -8.124952 -1.699514 270)
			(size 0.4318 0.4318)
			(layers "F.Cu" "F.Mask" "F.Paste")
			(net "GND")
		)
		(pad "BR39" smd circle
			(at -6.49732 -1.699514 270)
			(size 0.4318 0.4318)
			(layers "F.Cu" "F.Mask" "F.Paste")
			(net "GND")
		)
		(pad "BR41" smd circle
			(at -4.869434 -1.699514 270)
			(size 0.4318 0.4318)
			(layers "F.Cu" "F.Mask" "F.Paste")
			(net "GND")
		)
		(pad "BR43" smd circle
			(at -3.241802 -1.699514 270)
			(size 0.4318 0.4318)
			(layers "F.Cu" "F.Mask" "F.Paste")
			(net "GND")
		)
		(pad "BR45" smd circle
			(at -1.613916 -1.699514 270)
			(size 0.4318 0.4318)
			(layers "F.Cu" "F.Mask" "F.Paste")
			(net "GND")
		)
		(pad "BR48" smd circle
			(at 2.427732 -1.589532 270)
			(size 0.4318 0.4318)
			(layers "F.Cu" "F.Mask" "F.Paste")
			(net "GND")
		)
		(pad "BR50" smd circle
			(at 4.055618 -1.589532 270)
			(size 0.4318 0.4318)
			(layers "F.Cu" "F.Mask" "F.Paste")
			(net "GND")
		)
		(pad "BR52" smd circle
			(at 5.68325 -1.589532 270)
			(size 0.4318 0.4318)
			(layers "F.Cu" "F.Mask" "F.Paste")
			(net "GND")
		)
		(pad "BR54" smd circle
			(at 7.311136 -1.589532 270)
			(size 0.4318 0.4318)
			(layers "F.Cu" "F.Mask" "F.Paste")
			(net "GND")
		)
		(pad "BR56" smd circle
			(at 8.939022 -1.589532 270)
			(size 0.4318 0.4318)
			(layers "F.Cu" "F.Mask" "F.Paste")
			(net "GND")
		)
		(pad "BR58" smd circle
			(at 10.566654 -1.589532 270)
			(size 0.4318 0.4318)
			(layers "F.Cu" "F.Mask" "F.Paste")
			(net "GND")
		)
		(pad "BR60" smd circle
			(at 12.19454 -1.589532 270)
			(size 0.4318 0.4318)
			(layers "F.Cu" "F.Mask" "F.Paste")
			(net "PVCCIN_CPU0")
		)
		(pad "BR62" smd circle
			(at 13.822426 -1.589532 270)
			(size 0.4318 0.4318)
			(layers "F.Cu" "F.Mask" "F.Paste")
			(net "PVCCIN_CPU0")
		)
		(pad "BR64" smd circle
			(at 15.450058 -1.589532 270)
			(size 0.4318 0.4318)
			(layers "F.Cu" "F.Mask" "F.Paste")
			(net "GND")
		)
		(pad "BR66" smd circle
			(at 17.07769 -1.589532 270)
			(size 0.4318 0.4318)
			(layers "F.Cu" "F.Mask" "F.Paste")
			(net "GND")
		)
		(pad "BR68" smd circle
			(at 18.705576 -1.589532 270)
			(size 0.4318 0.4318)
			(layers "F.Cu" "F.Mask" "F.Paste")
			(net "GND")
		)
		(pad "BR70" smd circle
			(at 20.333462 -1.589532 270)
			(size 0.4318 0.4318)
			(layers "F.Cu" "F.Mask" "F.Paste")
			(net "GND")
		)
		(pad "BR72" smd circle
			(at 21.961094 -1.589532 270)
			(size 0.4318 0.4318)
			(layers "F.Cu" "F.Mask" "F.Paste")
			(net "GND")
		)
		(pad "BR74" smd circle
			(at 23.58898 -1.589532 270)
			(size 0.4318 0.4318)
			(layers "F.Cu" "F.Mask" "F.Paste")
			(net "GND")
		)
		(pad "BR76" smd circle
			(at 25.216612 -1.589532 270)
			(size 0.4318 0.4318)
			(layers "F.Cu" "F.Mask" "F.Paste")
			(net "GND")
		)
		(pad "BR78" smd circle
			(at 26.844498 -1.589532 270)
			(size 0.4318 0.4318)
			(layers "F.Cu" "F.Mask" "F.Paste")
			(net "PVCCIN_CPU0")
		)
		(pad "BR80" smd circle
			(at 28.472384 -1.589532 270)
			(size 0.4318 0.4318)
			(layers "F.Cu" "F.Mask" "F.Paste")
			(net "GND")
		)
		(pad "BR82" smd circle
			(at 30.100016 -1.589532 270)
			(size 0.4318 0.4318)
			(layers "F.Cu" "F.Mask" "F.Paste")
			(net "GND")
		)
		(pad "BR84" smd circle
			(at 31.727902 -1.589532 270)
			(size 0.4318 0.4318)
			(layers "F.Cu" "F.Mask" "F.Paste")
			(net "GND")
		)
		(pad "BR86" smd circle
			(at 33.355534 -1.589532 270)
			(size 0.4318 0.4318)
			(layers "F.Cu" "F.Mask" "F.Paste")
			(net "GND")
		)
		(pad "BR88" smd circle
			(at 34.98342 -1.589532 270)
			(size 0.4318 0.4318)
			(layers "F.Cu" "F.Mask" "F.Paste")
			(net "GND")
		)
		(pad "BR90" smd oval
			(at 36.611306 -1.589532)
			(size 0.381 0.4826)
			(drill
				(offset 0 -0.0508)
			)
			(layers "F.Cu" "F.Mask" "F.Paste")
			(net "GND")
		)
		(pad "BT2" smd oval
			(at -36.611306 -1.229614 180)
			(size 0.381 0.4826)
			(drill
				(offset 0 -0.0508)
			)
			(layers "F.Cu" "F.Mask" "F.Paste")
			(net "UPI_CPU0_CPU1_P0P1_DN<23>")
		)
		(pad "BT4" smd circle
			(at -34.98342 -1.229614 270)
			(size 0.4318 0.4318)
			(layers "F.Cu" "F.Mask" "F.Paste")
			(net "GND")
		)
		(pad "BT6" smd circle
			(at -33.355534 -1.229614 270)
			(size 0.4318 0.4318)
			(layers "F.Cu" "F.Mask" "F.Paste")
			(net "UPI_CPU1_CPU0_P1P0_DN<23>")
		)
		(pad "BT8" smd circle
			(at -31.727902 -1.229614 270)
			(size 0.4318 0.4318)
			(layers "F.Cu" "F.Mask" "F.Paste")
			(net "GND")
		)
		(pad "BT10" smd circle
			(at -30.100016 -1.229614 270)
			(size 0.4318 0.4318)
			(layers "F.Cu" "F.Mask" "F.Paste")
			(net "P5E_CPU0_PE1_RX_DP<9>")
		)
		(pad "BT12" smd circle
			(at -28.472384 -1.229614 270)
			(size 0.4318 0.4318)
			(layers "F.Cu" "F.Mask" "F.Paste")
			(net "GND")
		)
		(pad "BT14" smd circle
			(at -26.844498 -1.229614 270)
			(size 0.4318 0.4318)
			(layers "F.Cu" "F.Mask" "F.Paste")
			(net "P5E_CPU0_PE1_TX_DP<9>")
		)
		(pad "BT16" smd circle
			(at -25.216612 -1.229614 270)
			(size 0.4318 0.4318)
			(layers "F.Cu" "F.Mask" "F.Paste")
			(net "GND")
		)
		(pad "BT18" smd circle
			(at -23.58898 -1.229614 270)
			(size 0.4318 0.4318)
			(layers "F.Cu" "F.Mask" "F.Paste")
			(net "DMI_CPU0_PCH_RX_C_DP<7>")
		)
		(pad "BT20" smd circle
			(at -21.961094 -1.229614 270)
			(size 0.4318 0.4318)
			(layers "F.Cu" "F.Mask" "F.Paste")
			(net "GND")
		)
		(pad "BT22" smd circle
			(at -20.333462 -1.229614 270)
			(size 0.4318 0.4318)
			(layers "F.Cu" "F.Mask" "F.Paste")
			(net "I3C_SPD_DDRABCD_CPU0_SCL")
		)
		(pad "BT24" smd circle
			(at -18.705576 -1.229614 270)
			(size 0.4318 0.4318)
			(layers "F.Cu" "F.Mask" "F.Paste")
			(net "JTAG_DBP_CPU0_GTL_R_TCK")
		)
		(pad "BT26" smd circle
			(at -17.07769 -1.229614 270)
			(size 0.4318 0.4318)
			(layers "F.Cu" "F.Mask" "F.Paste")
			(net "PU_CPU0_TXT_AGENT")
		)
		(pad "BT28" smd circle
			(at -15.450058 -1.229614 270)
			(size 0.4318 0.4318)
			(layers "F.Cu" "F.Mask" "F.Paste")
			(net "TP_TRC_CPU0_PTI<9>")
		)
		(pad "BT30" smd circle
			(at -13.822426 -1.229614 270)
			(size 0.4318 0.4318)
			(layers "F.Cu" "F.Mask" "F.Paste")
			(net "TP_TRC_CPU0_PTI<11>")
		)
		(pad "BT32" smd circle
			(at -12.19454 -1.229614 270)
			(size 0.4318 0.4318)
			(layers "F.Cu" "F.Mask" "F.Paste")
			(net "PVCCIN_CPU0")
		)
		(pad "BT34" smd circle
			(at -10.566654 -1.229614 270)
			(size 0.4318 0.4318)
			(layers "F.Cu" "F.Mask" "F.Paste")
			(net "PVCCIN_CPU0")
		)
		(pad "BT36" smd circle
			(at -8.939022 -1.229614 270)
			(size 0.4318 0.4318)
			(layers "F.Cu" "F.Mask" "F.Paste")
			(net "PVCCIN_CPU0")
		)
		(pad "BT38" smd circle
			(at -7.311136 -1.229614 270)
			(size 0.4318 0.4318)
			(layers "F.Cu" "F.Mask" "F.Paste")
			(net "PVCCIN_CPU0")
		)
		(pad "BT40" smd circle
			(at -5.68325 -1.229614 270)
			(size 0.4318 0.4318)
			(layers "F.Cu" "F.Mask" "F.Paste")
			(net "PVCCIN_CPU0")
		)
		(pad "BT42" smd circle
			(at -4.055618 -1.229614 270)
			(size 0.4318 0.4318)
			(layers "F.Cu" "F.Mask" "F.Paste")
			(net "PVCCIN_CPU0")
		)
		(pad "BT44" smd circle
			(at -2.427732 -1.229614 270)
			(size 0.4318 0.4318)
			(layers "F.Cu" "F.Mask" "F.Paste")
			(net "PVCCIN_CPU0")
		)
		(pad "BT47" smd circle
			(at 1.613916 -1.119886 270)
			(size 0.4318 0.4318)
			(layers "F.Cu" "F.Mask" "F.Paste")
			(net "PVCCIN_CPU0")
		)
		(pad "BT49" smd circle
			(at 3.241802 -1.119886 270)
			(size 0.4318 0.4318)
			(layers "F.Cu" "F.Mask" "F.Paste")
			(net "PVCCIN_CPU0")
		)
		(pad "BT51" smd circle
			(at 4.869434 -1.119886 270)
			(size 0.4318 0.4318)
			(layers "F.Cu" "F.Mask" "F.Paste")
			(net "PVCCIN_CPU0")
		)
		(pad "BT53" smd circle
			(at 6.49732 -1.119886 270)
			(size 0.4318 0.4318)
			(layers "F.Cu" "F.Mask" "F.Paste")
			(net "PVCCIN_CPU0")
		)
		(pad "BT55" smd circle
			(at 8.124952 -1.119886 270)
			(size 0.4318 0.4318)
			(layers "F.Cu" "F.Mask" "F.Paste")
			(net "PVCCIN_CPU0")
		)
		(pad "BT57" smd circle
			(at 9.752838 -1.119886 270)
			(size 0.4318 0.4318)
			(layers "F.Cu" "F.Mask" "F.Paste")
			(net "PVCCIN_CPU0")
		)
		(pad "BT59" smd circle
			(at 11.380724 -1.119886 270)
			(size 0.4318 0.4318)
			(layers "F.Cu" "F.Mask" "F.Paste")
			(net "PVCCIN_CPU0")
		)
		(pad "BT61" smd circle
			(at 13.008356 -1.119886 270)
			(size 0.4318 0.4318)
			(layers "F.Cu" "F.Mask" "F.Paste")
			(net "PVCCIN_CPU0")
		)
		(pad "BT63" smd circle
			(at 14.635988 -1.119886 270)
			(size 0.4318 0.4318)
			(layers "F.Cu" "F.Mask" "F.Paste")
			(net "PVCCIN_CPU0")
		)
		(pad "BT65" smd circle
			(at 16.263874 -1.119886 270)
			(size 0.4318 0.4318)
			(layers "F.Cu" "F.Mask" "F.Paste")
			(net "PVCCIN_CPU0")
		)
		(pad "BT67" smd circle
			(at 17.89176 -1.119886 270)
			(size 0.4318 0.4318)
			(layers "F.Cu" "F.Mask" "F.Paste")
			(net "PVCCIN_CPU0")
		)
		(pad "BT69" smd circle
			(at 19.519392 -1.119886 270)
			(size 0.4318 0.4318)
			(layers "F.Cu" "F.Mask" "F.Paste")
			(net "PVCCIN_CPU0")
		)
		(pad "BT71" smd circle
			(at 21.147278 -1.119886 270)
			(size 0.4318 0.4318)
			(layers "F.Cu" "F.Mask" "F.Paste")
			(net "PVCCIN_CPU0")
		)
		(pad "BT73" smd circle
			(at 22.77491 -1.119886 270)
			(size 0.4318 0.4318)
			(layers "F.Cu" "F.Mask" "F.Paste")
			(net "PVCCIN_CPU0")
		)
		(pad "BT75" smd circle
			(at 24.402796 -1.119886 270)
			(size 0.4318 0.4318)
			(layers "F.Cu" "F.Mask" "F.Paste")
			(net "PVCCIN_CPU0")
		)
		(pad "BT77" smd circle
			(at 26.030682 -1.119886 270)
			(size 0.4318 0.4318)
			(layers "F.Cu" "F.Mask" "F.Paste")
			(net "PVCCIN_CPU0")
		)
		(pad "BT79" smd circle
			(at 27.658314 -1.119886 270)
			(size 0.4318 0.4318)
			(layers "F.Cu" "F.Mask" "F.Paste")
			(net "PVCCIN_CPU0")
		)
		(pad "BT81" smd circle
			(at 29.2862 -1.119886 270)
			(size 0.4318 0.4318)
			(layers "F.Cu" "F.Mask" "F.Paste")
			(net "PVCCIN_CPU0")
		)
		(pad "BT83" smd circle
			(at 30.914086 -1.119886 270)
			(size 0.4318 0.4318)
			(layers "F.Cu" "F.Mask" "F.Paste")
			(net "PVCCIN_CPU0")
		)
		(pad "BT85" smd circle
			(at 32.541718 -1.119886 270)
			(size 0.4318 0.4318)
			(layers "F.Cu" "F.Mask" "F.Paste")
			(net "PVCCIN_CPU0")
		)
		(pad "BT87" smd circle
			(at 34.169604 -1.119886 270)
			(size 0.4318 0.4318)
			(layers "F.Cu" "F.Mask" "F.Paste")
			(net "PVCCIN_CPU0")
		)
		(pad "BT89" smd circle
			(at 35.797236 -1.119886 270)
			(size 0.4318 0.4318)
			(layers "F.Cu" "F.Mask" "F.Paste")
			(net "PVCCIN_CPU0")
		)
		(pad "BU3" smd circle
			(at -35.797236 -0.759714 270)
			(size 0.4318 0.4318)
			(layers "F.Cu" "F.Mask" "F.Paste")
			(net "UPI_CPU0_CPU1_P0P1_DP<23>")
		)
		(pad "BU5" smd circle
			(at -34.169604 -0.759714 270)
			(size 0.4318 0.4318)
			(layers "F.Cu" "F.Mask" "F.Paste")
			(net "UPI_CPU1_CPU0_P1P0_DP<23>")
		)
		(pad "BU7" smd circle
			(at -32.541718 -0.759714 270)
			(size 0.4318 0.4318)
			(layers "F.Cu" "F.Mask" "F.Paste")
			(net "GND")
		)
		(pad "BU9" smd circle
			(at -30.914086 -0.759714 270)
			(size 0.4318 0.4318)
			(layers "F.Cu" "F.Mask" "F.Paste")
			(net "P5E_CPU0_PE1_RX_DP<8>")
		)
		(pad "BU11" smd circle
			(at -29.2862 -0.759714 270)
			(size 0.4318 0.4318)
			(layers "F.Cu" "F.Mask" "F.Paste")
			(net "VSENSE_PVCCD_HV_CPU0_DP")
		)
		(pad "BU13" smd circle
			(at -27.658314 -0.759714 270)
			(size 0.4318 0.4318)
			(layers "F.Cu" "F.Mask" "F.Paste")
			(net "P5E_CPU0_PE1_TX_DN<9>")
		)
		(pad "BU15" smd circle
			(at -26.030682 -0.759714 270)
			(size 0.4318 0.4318)
			(layers "F.Cu" "F.Mask" "F.Paste")
			(net "GND")
		)
		(pad "BU17" smd circle
			(at -24.402796 -0.759714 270)
			(size 0.4318 0.4318)
			(layers "F.Cu" "F.Mask" "F.Paste")
			(net "DMI_CPU0_PCH_RX_C_DN<7>")
		)
		(pad "BU19" smd circle
			(at -22.77491 -0.759714 270)
			(size 0.4318 0.4318)
			(layers "F.Cu" "F.Mask" "F.Paste")
			(net "GND")
		)
		(pad "BU21" smd circle
			(at -21.147278 -0.759714 270)
			(size 0.4318 0.4318)
			(layers "F.Cu" "F.Mask" "F.Paste")
			(net "GND")
		)
		(pad "BU23" smd circle
			(at -19.519392 -0.759714 270)
			(size 0.4318 0.4318)
			(layers "F.Cu" "F.Mask" "F.Paste")
			(net "GND")
		)
		(pad "BU25" smd circle
			(at -17.89176 -0.759714 270)
			(size 0.4318 0.4318)
			(layers "F.Cu" "F.Mask" "F.Paste")
			(net "GND")
		)
		(pad "BU27" smd circle
			(at -16.263874 -0.759714 270)
			(size 0.4318 0.4318)
			(layers "F.Cu" "F.Mask" "F.Paste")
			(net "TP_TRC_CPU0_PTI<8>")
		)
		(pad "BU29" smd circle
			(at -14.635988 -0.759714 270)
			(size 0.4318 0.4318)
			(layers "F.Cu" "F.Mask" "F.Paste")
			(net "TP_TRC_CPU0_PTI<10>")
		)
		(pad "BU31" smd circle
			(at -13.008356 -0.759714 270)
			(size 0.4318 0.4318)
			(layers "F.Cu" "F.Mask" "F.Paste")
			(net "GND")
		)
		(pad "BU33" smd circle
			(at -11.380724 -0.759714 270)
			(size 0.4318 0.4318)
			(layers "F.Cu" "F.Mask" "F.Paste")
			(net "PVCCIN_CPU0")
		)
		(pad "BU35" smd circle
			(at -9.752838 -0.759714 270)
			(size 0.4318 0.4318)
			(layers "F.Cu" "F.Mask" "F.Paste")
			(net "PVCCIN_CPU0")
		)
		(pad "BU37" smd circle
			(at -8.124952 -0.759714 270)
			(size 0.4318 0.4318)
			(layers "F.Cu" "F.Mask" "F.Paste")
			(net "PVCCIN_CPU0")
		)
		(pad "BU39" smd circle
			(at -6.49732 -0.759714 270)
			(size 0.4318 0.4318)
			(layers "F.Cu" "F.Mask" "F.Paste")
			(net "PVCCIN_CPU0")
		)
		(pad "BU41" smd circle
			(at -4.869434 -0.759714 270)
			(size 0.4318 0.4318)
			(layers "F.Cu" "F.Mask" "F.Paste")
			(net "PVCCIN_CPU0")
		)
		(pad "BU43" smd circle
			(at -3.241802 -0.759714 270)
			(size 0.4318 0.4318)
			(layers "F.Cu" "F.Mask" "F.Paste")
			(net "PVCCIN_CPU0")
		)
		(pad "BU45" smd circle
			(at -1.613916 -0.759714 270)
			(size 0.4318 0.4318)
			(layers "F.Cu" "F.Mask" "F.Paste")
			(net "PVCCIN_CPU0")
		)
		(pad "BU48" smd circle
			(at 2.427732 -0.649732 270)
			(size 0.4318 0.4318)
			(layers "F.Cu" "F.Mask" "F.Paste")
			(net "PVCCIN_CPU0")
		)
		(pad "BU50" smd circle
			(at 4.055618 -0.649732 270)
			(size 0.4318 0.4318)
			(layers "F.Cu" "F.Mask" "F.Paste")
			(net "PVCCIN_CPU0")
		)
		(pad "BU52" smd circle
			(at 5.68325 -0.649732 270)
			(size 0.4318 0.4318)
			(layers "F.Cu" "F.Mask" "F.Paste")
			(net "PVCCIN_CPU0")
		)
		(pad "BU54" smd circle
			(at 7.311136 -0.649732 270)
			(size 0.4318 0.4318)
			(layers "F.Cu" "F.Mask" "F.Paste")
			(net "PVCCIN_CPU0")
		)
		(pad "BU56" smd circle
			(at 8.939022 -0.649732 270)
			(size 0.4318 0.4318)
			(layers "F.Cu" "F.Mask" "F.Paste")
			(net "PVCCIN_CPU0")
		)
		(pad "BU58" smd circle
			(at 10.566654 -0.649732 270)
			(size 0.4318 0.4318)
			(layers "F.Cu" "F.Mask" "F.Paste")
			(net "PVCCIN_CPU0")
		)
		(pad "BU60" smd circle
			(at 12.19454 -0.649732 270)
			(size 0.4318 0.4318)
			(layers "F.Cu" "F.Mask" "F.Paste")
			(net "PVCCIN_CPU0")
		)
		(pad "BU62" smd circle
			(at 13.822426 -0.649732 270)
			(size 0.4318 0.4318)
			(layers "F.Cu" "F.Mask" "F.Paste")
			(net "PVCCIN_CPU0")
		)
		(pad "BU64" smd circle
			(at 15.450058 -0.649732 270)
			(size 0.4318 0.4318)
			(layers "F.Cu" "F.Mask" "F.Paste")
			(net "PVCCIN_CPU0")
		)
		(pad "BU66" smd circle
			(at 17.07769 -0.649732 270)
			(size 0.4318 0.4318)
			(layers "F.Cu" "F.Mask" "F.Paste")
			(net "PVCCIN_CPU0")
		)
		(pad "BU68" smd circle
			(at 18.705576 -0.649732 270)
			(size 0.4318 0.4318)
			(layers "F.Cu" "F.Mask" "F.Paste")
			(net "PVCCIN_CPU0")
		)
		(pad "BU70" smd circle
			(at 20.333462 -0.649732 270)
			(size 0.4318 0.4318)
			(layers "F.Cu" "F.Mask" "F.Paste")
			(net "PVCCIN_CPU0")
		)
	)
)
